(kicad_pcb
	(version 20221018)
	(generator pcbnew)
	(general
    (thickness 1.518)
  )
	(paper "A4")
	(title_block
    (title "Kria K26 Devboard")
    (date "2024-03-26")
    (rev "1.2.5")
    (comment 1 "www.antmicro.com")
    (comment 2 "Antmicro Ltd.")
		(comment 9 "footprints 638-646 of 660")
	)
	(layers
    (0 "F.Cu" mixed)
    (1 "In1.Cu" power)
    (2 "In2.Cu" mixed)
    (3 "In3.Cu" power)
    (4 "In4.Cu" mixed)
    (5 "In5.Cu" power)
    (6 "In6.Cu" mixed)
    (31 "B.Cu" power)
    (32 "B.Adhes" user "B.Adhesive")
    (33 "F.Adhes" user "F.Adhesive")
    (34 "B.Paste" user)
    (35 "F.Paste" user)
    (36 "B.SilkS" user "B.Silkscreen")
    (37 "F.SilkS" user "F.Silkscreen")
    (38 "B.Mask" user)
    (39 "F.Mask" user)
    (40 "Dwgs.User" user "User.Drawings")
    (41 "Cmts.User" user "User.Comments")
    (42 "Eco1.User" user "User.Eco1")
    (43 "Eco2.User" user "User.Eco2")
    (44 "Edge.Cuts" user)
    (45 "Margin" user)
    (46 "B.CrtYd" user "B.Courtyard")
    (47 "F.CrtYd" user "F.Courtyard")
    (48 "B.Fab" user)
    (49 "F.Fab" user)
  )
	(footprint "kria-k26-devboard-footprints:R_0402_1005Metric" (layer "B.Cu")
    (at 140.475 120.35 180)
    (descr "Resistor SMD 0402")
    (tags "resistor SMD 0402")
    (property "Author" "Antmicro")
    (property "License" "Apache-2.0")
    (property "MPN" "CR0402-FX-1002GLF")
    (property "Manufacturer" "Bourns")
    (property "Sheetfile" "debug.kicad_sch")
    (property "Sheetname" "Debug and JTAG")
    (property "Tolerance" "1%")
    (property "Val" "10k")
    (property "ki_description" "10k resistor in 0402 package with 1% tolerance")
    (attr smd)
    (fp_text reference "R169" (at -3.685 -0.4) (layer "B.SilkS")
        (effects (font (size 0.7 0.7) (thickness 0.15)) (justify left bottom mirror))
    )
    (fp_text value "R_10k_0402" (at 0 -1.4) (layer "B.Fab") hide
        (effects (font (size 0.7 0.7) (thickness 0.15)) (justify left bottom mirror))
    )
    (fp_text user "License: Apache-2.0" (at -0.95 -5.169) (layer "B.Fab") hide
        (effects (font (size 0.7 0.7) (thickness 0.15)) (justify left bottom mirror))
    )
    (fp_text user "${REFERENCE}" (at -0.95 -3.168) (layer "B.Fab") hide
        (effects (font (size 0.7 0.7) (thickness 0.15)) (justify left bottom mirror))
    )
    (fp_text user "Author: Antmicro" (at -0.95 -4.169) (layer "B.Fab") hide
        (effects (font (size 0.7 0.7) (thickness 0.15)) (justify left bottom mirror))
    )
    (fp_rect (start -0.93 0.47) (end 0.93 -0.47)
      (stroke (width 0.05) (type solid)) (fill none) (layer "B.CrtYd"))
    (fp_rect (start -0.5 0.25) (end 0.5 -0.25)
      (stroke (width 0.15) (type solid)) (fill none) (layer "B.Fab"))
    (pad "1" smd roundrect (at -0.485 0 180) (size 0.59 0.64) (layers "B.Cu" "B.Paste" "B.Mask") (roundrect_rratio 0.25)
      (net 169 "/Debug and JTAG/JTAG_VCCO_ON") (pintype "passive"))
    (pad "2" smd roundrect (at 0.485 0 180) (size 0.59 0.64) (layers "B.Cu" "B.Paste" "B.Mask") (roundrect_rratio 0.25)
      (net 1 "GND") (pintype "passive"))
  )
	(footprint "kria-k26-devboard-footprints:SOT-416" (layer "B.Cu")
    (at 98 89.2)
    (descr "SOT-416")
    (tags "SOT-416")
    (property "Author" "Antmicro")
    (property "License" "Apache-2.0")
    (property "MPN" "DTC014TEBTL")
    (property "Manufacturer" "ROHM Semiconductor")
    (property "Sheetfile" "k26_som.kicad_sch")
    (property "Sheetname" "Xilinx K26 SOM")
    (property "ki_description" "Digital NPN Transistor, 10k/NONE, EMT-3")
    (attr smd)
    (fp_text reference "Q19" (at -0.91 0.36 180) (layer "B.SilkS")
        (effects (font (size 0.7 0.7) (thickness 0.15)) (justify left bottom mirror))
    )
    (fp_text value "DTC014T_SOT-416" (at 0 -2 180) (layer "B.Fab") hide
        (effects (font (size 0.7 0.7) (thickness 0.15)) (justify left bottom mirror))
    )
    (fp_text user "${REFERENCE}" (at -1 -3.4 180) (layer "B.Fab") hide
        (effects (font (size 0.7 0.7) (thickness 0.15)) (justify left bottom mirror))
    )
    (fp_text user "License: Apache-2.0" (at -1 -5.802 180) (layer "B.Fab") hide
        (effects (font (size 0.7 0.7) (thickness 0.15)) (justify left bottom mirror))
    )
    (fp_text user "Author: Antmicro" (at -1 -4.602 180) (layer "B.Fab") hide
        (effects (font (size 0.7 0.7) (thickness 0.15)) (justify left bottom mirror))
    )
    (fp_line (start -0.5 0.15) (end -0.5 -0.15)
      (stroke (width 0.15) (type solid)) (layer "B.SilkS"))
    (fp_line (start 0.5 -0.9) (end -0.5 -0.9)
      (stroke (width 0.15) (type solid)) (layer "B.SilkS"))
    (fp_line (start 0.5 -0.9) (end 0.5 -0.7)
      (stroke (width 0.15) (type solid)) (layer "B.SilkS"))
    (fp_line (start 0.508 0.9) (end -0.5 0.9)
      (stroke (width 0.15) (type solid)) (layer "B.SilkS"))
    (fp_line (start 0.508 0.9) (end 0.508 0.592)
      (stroke (width 0.15) (type solid)) (layer "B.SilkS"))
    (fp_rect (start -1 1.05) (end 1 -1.05)
      (stroke (width 0.05) (type solid)) (fill none) (layer "B.CrtYd"))
    (fp_line (start -0.05 0.9) (end -0.45 0.5)
      (stroke (width 0.15) (type solid)) (layer "B.Fab"))
    (fp_rect (start 0.45 -0.9) (end -0.45 0.9)
      (stroke (width 0.15) (type solid)) (fill none) (layer "B.Fab"))
    (pad "1" smd rect (at -0.652 0.5) (size 0.6 0.5) (layers "B.Cu" "B.Paste" "B.Mask")
      (net 6 "/Xilinx K26 SOM/HDA20") (pinfunction "B") (pintype "input"))
    (pad "2" smd rect (at -0.652 -0.498) (size 0.6 0.5) (layers "B.Cu" "B.Paste" "B.Mask")
      (net 1 "GND") (pinfunction "E") (pintype "passive"))
    (pad "3" smd rect (at 0.65 0) (size 0.6 0.5) (layers "B.Cu" "B.Paste" "B.Mask")
      (net 431 "Net-(Q19-C)") (pinfunction "C") (pintype "passive"))
  )
	(footprint "kria-k26-devboard-footprints:R_0402_1005Metric" (layer "B.Cu")
    (at 130.33 63.75 -90)
    (descr "Resistor SMD 0402")
    (tags "resistor SMD 0402")
    (property "Author" "Antmicro")
    (property "License" "Apache-2.0")
    (property "MPN" "CR0402-FX-4302GLF")
    (property "Manufacturer" "Bourns")
    (property "Sheetfile" "usb.kicad_sch")
    (property "Sheetname" "USB")
    (property "Tolerance" "1%")
    (property "Val" "43k")
    (property "ki_description" "43k resistor in 0402 package with 1% tolerance")
    (attr smd)
    (fp_text reference "R174" (at -3.780421 -0.38 90) (layer "B.SilkS")
        (effects (font (size 0.7 0.7) (thickness 0.15)) (justify left bottom mirror))
    )
    (fp_text value "R_43k_0402" (at 0 -1.4 90) (layer "B.Fab") hide
        (effects (font (size 0.7 0.7) (thickness 0.15)) (justify left bottom mirror))
    )
    (fp_text user "License: Apache-2.0" (at -0.95 -5.169 90) (layer "B.Fab") hide
        (effects (font (size 0.7 0.7) (thickness 0.15)) (justify left bottom mirror))
    )
    (fp_text user "${REFERENCE}" (at -0.95 -3.168 90) (layer "B.Fab") hide
        (effects (font (size 0.7 0.7) (thickness 0.15)) (justify left bottom mirror))
    )
    (fp_text user "Author: Antmicro" (at -0.95 -4.169 90) (layer "B.Fab") hide
        (effects (font (size 0.7 0.7) (thickness 0.15)) (justify left bottom mirror))
    )
    (fp_rect (start -0.93 0.47) (end 0.93 -0.47)
      (stroke (width 0.05) (type solid)) (fill none) (layer "B.CrtYd"))
    (fp_rect (start -0.5 0.25) (end 0.5 -0.25)
      (stroke (width 0.15) (type solid)) (fill none) (layer "B.Fab"))
    (pad "1" smd roundrect (at -0.485 0 270) (size 0.59 0.64) (layers "B.Cu" "B.Paste" "B.Mask") (roundrect_rratio 0.25)
      (net 697 "Net-(U17-DP1_VBUS_MON)") (pintype "passive"))
    (pad "2" smd roundrect (at 0.485 0 270) (size 0.59 0.64) (layers "B.Cu" "B.Paste" "B.Mask") (roundrect_rratio 0.25)
      (net 64 "/USB/USB1_VBUS") (pintype "passive"))
  )
	(footprint "kria-k26-devboard-footprints:R_0402_1005Metric" (layer "B.Cu")
    (at 174.95 129.025 -90)
    (descr "Resistor SMD 0402")
    (tags "resistor SMD 0402")
    (property "Author" "Antmicro")
    (property "Current" "1A")
    (property "License" "Apache-2.0")
    (property "MPN" "ERJ2GE0R00X")
    (property "Manufacturer" "Panasonic")
    (property "Sheetfile" "dc-dc-conventers.kicad_sch")
    (property "Sheetname" "DC/DC conventers")
    (property "Tolerance" "")
    (property "Val" "0R")
    (property "ki_description" "0R resistor in 0402 package with unspecified tolerance")
    (attr smd)
    (fp_text reference "R165" (at 0.815 -0.37 90) (layer "B.SilkS")
        (effects (font (size 0.7 0.7) (thickness 0.15)) (justify left bottom mirror))
    )
    (fp_text value "R_0R_0402" (at 0 -1.4 90) (layer "B.Fab") hide
        (effects (font (size 0.7 0.7) (thickness 0.15)) (justify left bottom mirror))
    )
    (fp_text user "Author: Antmicro" (at -0.95 -4.169 90) (layer "B.Fab") hide
        (effects (font (size 0.7 0.7) (thickness 0.15)) (justify left bottom mirror))
    )
    (fp_text user "License: Apache-2.0" (at -0.95 -5.169 90) (layer "B.Fab") hide
        (effects (font (size 0.7 0.7) (thickness 0.15)) (justify left bottom mirror))
    )
    (fp_text user "${REFERENCE}" (at -0.95 -3.168 90) (layer "B.Fab") hide
        (effects (font (size 0.7 0.7) (thickness 0.15)) (justify left bottom mirror))
    )
    (fp_rect (start -0.93 0.47) (end 0.93 -0.47)
      (stroke (width 0.05) (type solid)) (fill none) (layer "B.CrtYd"))
    (fp_rect (start -0.5 0.25) (end 0.5 -0.25)
      (stroke (width 0.15) (type solid)) (fill none) (layer "B.Fab"))
    (pad "1" smd roundrect (at -0.485 0 270) (size 0.59 0.64) (layers "B.Cu" "B.Paste" "B.Mask") (roundrect_rratio 0.25)
      (net 774 "/Power Supply/DC/DC conventers/SOM_5V_FB") (pintype "passive"))
    (pad "2" smd roundrect (at 0.485 0 270) (size 0.59 0.64) (layers "B.Cu" "B.Paste" "B.Mask") (roundrect_rratio 0.25)
      (net 773 "/Power Supply/DC/DC conventers/SOM_5V_OUT") (pintype "passive"))
  )
	(footprint "kria-k26-devboard-footprints:R_0603_1608Metric" (layer "B.Cu")
    (at 136.3 85.55)
    (descr "Resistor SMD 0603")
    (tags "resistor SMD 0603")
    (property "Author" "Antmicro")
    (property "License" "Apache-2.0")
    (property "MPN" "PMR03EZPJ000")
    (property "Manufacturer" "ROHM Semiconductor")
    (property "Max. Curr." "22.4A")
    (property "Sheetfile" "dc-dc-conventers.kicad_sch")
    (property "Sheetname" "DC/DC conventers")
    (property "Val" "0R")
    (property "ki_description" "Metal strip 0Ohm jumper 22.4A")
    (property "ki_keywords" "Metal strip 0Ohm jumper 22.4A high power hpwr current")
    (attr smd)
    (fp_text reference "R163" (at 1.39 1.56 180) (layer "B.SilkS")
        (effects (font (size 0.7 0.7) (thickness 0.15)) (justify left bottom mirror))
    )
    (fp_text value "R_0R_22.4A_0603" (at 0 -1.6 180) (layer "B.Fab") hide
        (effects (font (size 0.7 0.7) (thickness 0.15)) (justify left bottom mirror))
    )
    (fp_text user "Author: Antmicro" (at -1.25 -4.9 180) (layer "B.Fab") hide
        (effects (font (size 0.7 0.7) (thickness 0.15)) (justify left bottom mirror))
    )
    (fp_text user "License: Apache-2.0" (at -1.25 -5.9 180) (layer "B.Fab") hide
        (effects (font (size 0.7 0.7) (thickness 0.15)) (justify left bottom mirror))
    )
    (fp_text user "${REFERENCE}" (at -1.25 -3.898 180) (layer "B.Fab") hide
        (effects (font (size 0.7 0.7) (thickness 0.15)) (justify left bottom mirror))
    )
    (fp_line (start -0.3 -0.3) (end 0.3 -0.3)
      (stroke (width 0.15) (type solid)) (layer "B.SilkS"))
    (fp_line (start -0.3 0.3) (end 0.3 0.3)
      (stroke (width 0.15) (type solid)) (layer "B.SilkS"))
    (fp_rect (start -1.25 0.7) (end 1.25 -0.7)
      (stroke (width 0.05) (type solid)) (fill none) (layer "B.CrtYd"))
    (fp_rect (start -0.8 0.4) (end 0.8 -0.4)
      (stroke (width 0.15) (type solid)) (fill none) (layer "B.Fab"))
    (pad "1" smd roundrect (at -0.7 0) (size 0.6 0.8) (layers "B.Cu" "B.Paste" "B.Mask") (roundrect_rratio 0.2)
      (net 766 "/Power Supply/DC/DC conventers/PS_2V5_OUT") (pintype "passive"))
    (pad "2" smd roundrect (at 0.7 0) (size 0.6 0.8) (layers "B.Cu" "B.Paste" "B.Mask") (roundrect_rratio 0.2)
      (net 16 "PS_2V5") (pintype "passive"))
  )
	(footprint "kria-k26-devboard-footprints:C_0402_1005Metric" (layer "B.Cu")
    (at 151.85 108.7)
    (descr "Capacitor SMD 0402")
    (tags "capacitor SMD 0402")
    (property "Author" "Antmicro")
    (property "Dielectric" "")
    (property "License" "Apache-2.0")
    (property "MPN" "C1005X6S1A105K050BC")
    (property "Manufacturer" "TDK")
    (property "Sheetfile" "debug.kicad_sch")
    (property "Sheetname" "Debug and JTAG")
    (property "Val" "1u")
    (property "Voltage" "")
    (property "ki_description" " ")
    (attr smd)
    (fp_text reference "C243" (at 3.832 0.35 180) (layer "B.SilkS")
        (effects (font (size 0.7 0.7) (thickness 0.15)) (justify left bottom mirror))
    )
    (fp_text value "C_1u_0402" (at 0 -1.4 180) (layer "B.Fab") hide
        (effects (font (size 0.7 0.7) (thickness 0.15)) (justify left bottom mirror))
    )
    (fp_text user "${REFERENCE}" (at -0.932 -3.168 180) (layer "B.Fab") hide
        (effects (font (size 0.7 0.7) (thickness 0.15)) (justify left bottom mirror))
    )
    (fp_text user "License: Apache-2.0" (at -0.932 -5.17 180) (layer "B.Fab") hide
        (effects (font (size 0.7 0.7) (thickness 0.15)) (justify left bottom mirror))
    )
    (fp_text user "Author: Antmicro" (at -0.932 -4.17 180) (layer "B.Fab") hide
        (effects (font (size 0.7 0.7) (thickness 0.15)) (justify left bottom mirror))
    )
    (fp_rect (start -0.94 0.47) (end 0.94 -0.47)
      (stroke (width 0.05) (type solid)) (fill none) (layer "B.CrtYd"))
    (fp_rect (start -0.499 0.249) (end 0.499 -0.249)
      (stroke (width 0.15) (type solid)) (fill none) (layer "B.Fab"))
    (pad "1" smd roundrect (at -0.484 0) (size 0.59 0.64) (layers "B.Cu" "B.Paste" "B.Mask") (roundrect_rratio 0.25)
      (net 187 "/Debug and JTAG/PD_3V3") (pintype "passive"))
    (pad "2" smd roundrect (at 0.484 0) (size 0.59 0.64) (layers "B.Cu" "B.Paste" "B.Mask") (roundrect_rratio 0.25)
      (net 1 "GND") (pintype "passive"))
  )
	(footprint "kria-k26-devboard-footprints:R_0402_1005Metric" (layer "B.Cu")
    (at 129.3 63.75 90)
    (descr "Resistor SMD 0402")
    (tags "resistor SMD 0402")
    (property "Author" "Antmicro")
    (property "License" "Apache-2.0")
    (property "MPN" "CR0402-FX-4992GLF")
    (property "Manufacturer" "Bourns")
    (property "Sheetfile" "usb.kicad_sch")
    (property "Sheetname" "USB")
    (property "Tolerance" "1%")
    (property "Val" "49k9")
    (property "ki_description" "49k9 resistor in 0402 package with 1% tolerance")
    (attr smd)
    (fp_text reference "R175" (at 3.780421 0.36 270) (layer "B.SilkS")
        (effects (font (size 0.7 0.7) (thickness 0.15)) (justify left bottom mirror))
    )
    (fp_text value "R_49k9_0402" (at 0 -1.4 270) (layer "B.Fab") hide
        (effects (font (size 0.7 0.7) (thickness 0.15)) (justify left bottom mirror))
    )
    (fp_text user "Author: Antmicro" (at -0.95 -4.169 270) (layer "B.Fab") hide
        (effects (font (size 0.7 0.7) (thickness 0.15)) (justify left bottom mirror))
    )
    (fp_text user "${REFERENCE}" (at -0.95 -3.168 270) (layer "B.Fab") hide
        (effects (font (size 0.7 0.7) (thickness 0.15)) (justify left bottom mirror))
    )
    (fp_text user "License: Apache-2.0" (at -0.95 -5.169 270) (layer "B.Fab") hide
        (effects (font (size 0.7 0.7) (thickness 0.15)) (justify left bottom mirror))
    )
    (fp_rect (start -0.93 0.47) (end 0.93 -0.47)
      (stroke (width 0.05) (type solid)) (fill none) (layer "B.CrtYd"))
    (fp_rect (start -0.5 0.25) (end 0.5 -0.25)
      (stroke (width 0.15) (type solid)) (fill none) (layer "B.Fab"))
    (pad "1" smd roundrect (at -0.485 0 90) (size 0.59 0.64) (layers "B.Cu" "B.Paste" "B.Mask") (roundrect_rratio 0.25)
      (net 1 "GND") (pintype "passive"))
    (pad "2" smd roundrect (at 0.485 0 90) (size 0.59 0.64) (layers "B.Cu" "B.Paste" "B.Mask") (roundrect_rratio 0.25)
      (net 697 "Net-(U17-DP1_VBUS_MON)") (pintype "passive"))
  )
	(footprint "kria-k26-devboard-footprints:R_0402_1005Metric" (layer "B.Cu")
    (at 93.575 136.35 -90)
    (descr "Resistor SMD 0402")
    (tags "resistor SMD 0402")
    (property "Author" "Antmicro")
    (property "Current" "1A")
    (property "License" "Apache-2.0")
    (property "MPN" "ERJ2GE0R00X")
    (property "Manufacturer" "Panasonic")
    (property "Sheetfile" "k26_som.kicad_sch")
    (property "Sheetname" "Xilinx K26 SOM")
    (property "Tolerance" "")
    (property "Val" "0R")
    (property "ki_description" "0R resistor in 0402 package with unspecified tolerance")
    (attr smd)
    (fp_text reference "R170" (at -1.36 0.615 90) (layer "B.SilkS")
        (effects (font (size 0.7 0.7) (thickness 0.15)) (justify left bottom mirror))
    )
    (fp_text value "R_0R_0402" (at 0 -1.4 90) (layer "B.Fab") hide
        (effects (font (size 0.7 0.7) (thickness 0.15)) (justify left bottom mirror))
    )
    (fp_text user "Author: Antmicro" (at -0.95 -4.169 90) (layer "B.Fab") hide
        (effects (font (size 0.7 0.7) (thickness 0.15)) (justify left bottom mirror))
    )
    (fp_text user "${REFERENCE}" (at -0.95 -3.168 90) (layer "B.Fab") hide
        (effects (font (size 0.7 0.7) (thickness 0.15)) (justify left bottom mirror))
    )
    (fp_text user "License: Apache-2.0" (at -0.95 -5.169 90) (layer "B.Fab") hide
        (effects (font (size 0.7 0.7) (thickness 0.15)) (justify left bottom mirror))
    )
    (fp_rect (start -0.93 0.47) (end 0.93 -0.47)
      (stroke (width 0.05) (type solid)) (fill none) (layer "B.CrtYd"))
    (fp_rect (start -0.5 0.25) (end 0.5 -0.25)
      (stroke (width 0.15) (type solid)) (fill none) (layer "B.Fab"))
    (pad "1" smd roundrect (at -0.485 0 270) (size 0.59 0.64) (layers "B.Cu" "B.Paste" "B.Mask") (roundrect_rratio 0.25)
      (net 1 "GND") (pintype "passive"))
    (pad "2" smd roundrect (at 0.485 0 270) (size 0.59 0.64) (layers "B.Cu" "B.Paste" "B.Mask") (roundrect_rratio 0.25)
      (net 438 "/Xilinx K26 SOM/VCC_BATT") (pintype "passive"))
  )
	(footprint "kria-k26-devboard-footprints:C_0402_1005Metric" (layer "B.Cu")
    (at 95.754999 67.675)
    (descr "Capacitor SMD 0402")
    (tags "capacitor SMD 0402")
    (property "Author" "Antmicro")
    (property "Dielectric" "")
    (property "License" "Apache-2.0")
    (property "MPN" "CC0402MRX5R5BB106")
    (property "Manufacturer" "Yaego")
    (property "Sheetfile" "dp.kicad_sch")
    (property "Sheetname" "Display Port")
    (property "Val" "10u")
    (property "Voltage" "")
    (property "ki_description" " ")
    (attr smd)
    (fp_text reference "C249" (at 3.705001 0.355 180) (layer "B.SilkS")
        (effects (font (size 0.7 0.7) (thickness 0.15)) (justify left bottom mirror))
    )
    (fp_text value "C_10u_0402" (at 0 -1.4 180) (layer "B.Fab") hide
        (effects (font (size 0.7 0.7) (thickness 0.15)) (justify left bottom mirror))
    )
    (fp_text user "${REFERENCE}" (at -0.932 -3.168 180) (layer "B.Fab") hide
        (effects (font (size 0.7 0.7) (thickness 0.15)) (justify left bottom mirror))
    )
    (fp_text user "Author: Antmicro" (at -0.932 -4.17 180) (layer "B.Fab") hide
        (effects (font (size 0.7 0.7) (thickness 0.15)) (justify left bottom mirror))
    )
    (fp_text user "License: Apache-2.0" (at -0.932 -5.17 180) (layer "B.Fab") hide
        (effects (font (size 0.7 0.7) (thickness 0.15)) (justify left bottom mirror))
    )
    (fp_rect (start -0.94 0.47) (end 0.94 -0.47)
      (stroke (width 0.05) (type solid)) (fill none) (layer "B.CrtYd"))
    (fp_rect (start -0.499 0.249) (end 0.499 -0.249)
      (stroke (width 0.15) (type solid)) (fill none) (layer "B.Fab"))
    (pad "1" smd roundrect (at -0.484 0) (size 0.59 0.64) (layers "B.Cu" "B.Paste" "B.Mask") (roundrect_rratio 0.25)
      (net 334 "Net-(J1-DP_PWR)") (pintype "passive"))
    (pad "2" smd roundrect (at 0.484 0) (size 0.59 0.64) (layers "B.Cu" "B.Paste" "B.Mask") (roundrect_rratio 0.25)
      (net 1 "GND") (pintype "passive"))
  )
)
